# T6G (Grand Teton) — schematic netlist excerpt (pin names and nets, part order shuffled) for the footprints in the layout excerpt that follows; sources: Cadence DE-HDL packaged netlist, KiCad conversion of 04192023_DAF0TMB3IC0_F0TG_MB_C_brd_V02_OCP.brd

R1442  Q_RES  100K 1% CHIP  pkg 0402LF  page 259 : A = P12V_MEM_CPU0 ; B = PWRGD_P12V_MEM_CPU0_EN

U248  74LVC1G32GW  IC  pkg SMLF  page 233
  I0  = GPU_FPGA_READY_R_N
  I1  = CLK_GEN2_GPU_FPGA_OE_R2_N
  GND  = GND
  O  = CLK_GEN2_GPU_FPGA_OE_OR_N
  VCC  = P3V3_AUX

(kicad_pcb
	(version 20260206)
	(generator "pcbnew")
	(generator_version "10.0")
	(general
		(thickness 1.6)
		(legacy_teardrops no)
	)
	(paper "A4")
	(title_block
		(title "04192023_DAF0TMB3IC0_F0TG_MB_C_brd_V02_OCP.brd")
		(comment 1 "Grand Teton / footprints 865-866 of 8354")
	)
	(layers
		(0 "F.Cu" signal "TOP")
		(4 "In1.Cu" signal "GND")
		(6 "In2.Cu" signal "IN1")
		(8 "In3.Cu" signal "GND1")
		(10 "In4.Cu" signal "IN2")
		(12 "In5.Cu" signal "GND2")
		(14 "In6.Cu" signal "IN3")
		(16 "In7.Cu" signal "GND3")
		(18 "In8.Cu" signal "VCC")
		(20 "In9.Cu" signal "VCC1")
		(22 "In10.Cu" signal "GND4")
		(24 "In11.Cu" signal "IN4")
		(26 "In12.Cu" signal "GND5")
		(28 "In13.Cu" signal "IN5")
		(30 "In14.Cu" signal "GND6")
		(32 "In15.Cu" signal "IN6")
		(34 "In16.Cu" signal "GND7")
		(2 "B.Cu" signal "BOTTOM")
		(9 "F.Adhes" user "F.Adhesive")
		(11 "B.Adhes" user "B.Adhesive")
		(13 "F.Paste" user "Package Geometry/Pastemask Top")
		(15 "B.Paste" user "Package Geometry/Pastemask Bottom")
		(5 "F.SilkS" user "Ref Des/Silkscreen Top")
		(7 "B.SilkS" user "Ref Des/Silkscreen Bottom")
		(1 "F.Mask" user "Board Geometry/Soldermask Top")
		(3 "B.Mask" user "Board Geometry/Soldermask Bottom")
		(17 "Dwgs.User" user "User.Drawings")
		(19 "Cmts.User" user "User.Comments")
		(21 "Eco1.User" user "User.Eco1")
		(23 "Eco2.User" user "User.Eco2")
		(25 "Edge.Cuts" user "Board Geometry/Outline")
		(27 "Margin" user)
		(31 "F.CrtYd" user "Package Geometry/Place Bound Top")
		(29 "B.CrtYd" user "Package Geometry/Place Bound Bottom")
		(35 "F.Fab" user "Ref Des/Assembly Top")
		(33 "B.Fab" user "Ref Des/Assembly Bottom")
	)
	(footprint ""
		(layer "F.Cu")
		(at 32.336994 -133.83895 180)
		(property "Reference" "U248"
			(at 1.415288 -2.52349 0)
			(unlocked yes)
			(layer "F.SilkS")
			(effects
				(font
					(size 0.7874 0.5842)
					(thickness 0.1524)
				)
				(justify left)
			)
		)
		(property "Value" ""
			(at 0 0 180)
			(layer "F.Fab")
			(effects
				(font
					(size 1.27 1.27)
				)
			)
		)
		(duplicate_pad_numbers_are_jumpers no)
		(fp_line
			(start 1.4986 1.100074)
			(end -1.4986 1.100074)
			(stroke
				(width 0.1524)
				(type default)
			)
			(layer "F.SilkS")
		)
		(fp_line
			(start 1.4986 -1.100074)
			(end 1.4986 1.100074)
			(stroke
				(width 0.1524)
				(type default)
			)
			(layer "F.SilkS")
		)
		(fp_line
			(start -1.4986 1.100074)
			(end -1.4986 -1.100074)
			(stroke
				(width 0.1524)
				(type default)
			)
			(layer "F.SilkS")
		)
		(fp_line
			(start -1.4986 -1.100074)
			(end 1.4986 -1.100074)
			(stroke
				(width 0.1524)
				(type default)
			)
			(layer "F.SilkS")
		)
		(fp_poly
			(pts
				(xy -0.956056 -1.274064) (xy -1.252728 -1.827784) (xy -0.627888 -1.827784)
			)
			(stroke
				(width 0)
				(type default)
			)
			(fill yes)
			(layer "F.SilkS")
		)
		(fp_line
			(start 0.67437 1.100074)
			(end -0.67437 1.100074)
			(stroke
				(width 0.1)
				(type default)
			)
			(layer "F.Fab")
		)
		(fp_line
			(start 0.67437 -1.100074)
			(end 0.67437 1.100074)
			(stroke
				(width 0.1)
				(type default)
			)
			(layer "F.Fab")
		)
		(fp_line
			(start -0.67437 1.100074)
			(end -0.67437 -1.100074)
			(stroke
				(width 0.1)
				(type default)
			)
			(layer "F.Fab")
		)
		(fp_line
			(start -0.67437 -1.100074)
			(end 0.67437 -1.100074)
			(stroke
				(width 0.1)
				(type default)
			)
			(layer "F.Fab")
		)
		(fp_poly
			(pts
				(xy -2.20472 -0.338328) (xy -2.20472 -0.963168) (xy -1.651 -0.635)
			)
			(stroke
				(width 0)
				(type default)
			)
			(fill yes)
			(layer "F.Fab")
		)
		(pad "1" smd rect
			(at -0.889 -0.649986 180)
			(size 1.016 0.381)
			(layers "F.Cu" "F.Mask" "F.Paste")
			(net "GPU_FPGA_READY_R_N")
		)
		(pad "2" smd rect
			(at -0.889 0 180)
			(size 1.016 0.381)
			(layers "F.Cu" "F.Mask" "F.Paste")
			(net "CLK_GEN2_GPU_FPGA_OE_R2_N")
		)
		(pad "3" smd rect
			(at -0.889 0.649986 180)
			(size 1.016 0.381)
			(layers "F.Cu" "F.Mask" "F.Paste")
			(net "GND")
		)
		(pad "4" smd rect
			(at 0.889 0.649986 180)
			(size 1.016 0.381)
			(layers "F.Cu" "F.Mask" "F.Paste")
			(net "CLK_GEN2_GPU_FPGA_OE_OR_N")
		)
		(pad "5" smd rect
			(at 0.889 -0.649986 180)
			(size 1.016 0.381)
			(layers "F.Cu" "F.Mask" "F.Paste")
			(net "P3V3_AUX")
		)
	)
	(footprint ""
		(layer "F.Cu")
		(at 103.170736 -127.787654 -90)
		(property "Reference" "R1442"
			(at 0 0 270)
			(layer "F.SilkS")
			(hide yes)
			(effects
				(font
					(size 1.27 1.27)
				)
			)
		)
		(property "Value" ""
			(at 0 0 270)
			(layer "F.Fab")
			(effects
				(font
					(size 1.27 1.27)
				)
			)
		)
		(duplicate_pad_numbers_are_jumpers no)
		(fp_line
			(start -0.7874 0.4064)
			(end -0.7874 -0.4064)
			(stroke
				(width 0.1524)
				(type default)
			)
			(layer "F.SilkS")
		)
		(fp_line
			(start 0.7874 0.4064)
			(end -0.7874 0.4064)
			(stroke
				(width 0.1524)
				(type default)
			)
			(layer "F.SilkS")
		)
		(fp_line
			(start -0.7874 -0.4064)
			(end 0.7874 -0.4064)
			(stroke
				(width 0.1524)
				(type default)
			)
			(layer "F.SilkS")
		)
		(fp_line
			(start 0.7874 -0.4064)
			(end 0.7874 0.4064)
			(stroke
				(width 0.1524)
				(type default)
			)
			(layer "F.SilkS")
		)
		(fp_line
			(start -0.67945 0.3048)
			(end -0.67945 -0.305054)
			(stroke
				(width 0.1)
				(type default)
			)
			(layer "F.Fab")
		)
		(fp_line
			(start -0.12065 0.3048)
			(end -0.67945 0.3048)
			(stroke
				(width 0.1)
				(type default)
			)
			(layer "F.Fab")
		)
		(fp_line
			(start 0.120396 0.3048)
			(end 0.120396 0.2794)
			(stroke
				(width 0.1)
				(type default)
			)
			(layer "F.Fab")
		)
		(fp_line
			(start 0.67945 0.3048)
			(end 0.120396 0.3048)
			(stroke
				(width 0.1)
				(type default)
			)
			(layer "F.Fab")
		)
		(fp_line
			(start -0.12065 0.2794)
			(end -0.12065 0.3048)
			(stroke
				(width 0.1)
				(type default)
			)
			(layer "F.Fab")
		)
		(fp_line
			(start 0.120396 0.2794)
			(end -0.12065 0.2794)
			(stroke
				(width 0.1)
				(type default)
			)
			(layer "F.Fab")
		)
		(fp_line
			(start -0.12065 -0.2794)
			(end 0.12065 -0.2794)
			(stroke
				(width 0.1)
				(type default)
			)
			(layer "F.Fab")
		)
		(fp_line
			(start 0.12065 -0.2794)
			(end 0.12065 -0.3048)
			(stroke
				(width 0.1)
				(type default)
			)
			(layer "F.Fab")
		)
		(fp_line
			(start 0.12065 -0.3048)
			(end 0.67945 -0.3048)
			(stroke
				(width 0.1)
				(type default)
			)
			(layer "F.Fab")
		)
		(fp_line
			(start 0.67945 -0.3048)
			(end 0.67945 0.3048)
			(stroke
				(width 0.1)
				(type default)
			)
			(layer "F.Fab")
		)
		(fp_line
			(start -0.67945 -0.305054)
			(end -0.12065 -0.305054)
			(stroke
				(width 0.1)
				(type default)
			)
			(layer "F.Fab")
		)
		(fp_line
			(start -0.12065 -0.305054)
			(end -0.12065 -0.2794)
			(stroke
				(width 0.1)
				(type default)
			)
			(layer "F.Fab")
		)
		(pad "1" smd circle
			(at -0.40005 0 270)
			(size 0 0)
			(layers "F.Cu" "F.Mask" "F.Paste")
			(net "P12V_MEM_CPU0")
		)
		(pad "2" smd circle
			(at 0.40005 0 270)
			(size 0 0)
			(layers "F.Cu" "F.Mask" "F.Paste")
			(net "PWRGD_P12V_MEM_CPU0_EN")
		)
	)
)
